(kicad_pcb
	(version 20260206)
	(generator "pcbnew")
	(generator_version "10.0")
	(general
		(thickness 1.6)
		(legacy_teardrops no)
	)
	(paper "A4")
	(title_block
		(title "timecard-production-celestica-r4006 — R4006-B0001-02_R01.brd")
		(comment 1 "Time Appliance Project (Time Card) / footprints 402-405 of 1113")
	)
	(layers
		(0 "F.Cu" signal "TOP")
		(4 "In1.Cu" signal "L02_GND1")
		(6 "In2.Cu" signal "L03_SIG1")
		(8 "In3.Cu" signal "L04_GND2")
		(10 "In4.Cu" signal "L05_VCC1")
		(12 "In5.Cu" signal "L06_VCC2")
		(14 "In6.Cu" signal "L07_GND3")
		(16 "In7.Cu" signal "L08_SIG2")
		(18 "In8.Cu" signal "L09_GND4")
		(2 "B.Cu" signal "BOTTOM")
		(9 "F.Adhes" user "F.Adhesive")
		(11 "B.Adhes" user "B.Adhesive")
		(13 "F.Paste" user "Package Geometry/Pastemask Top")
		(15 "B.Paste" user "Package Geometry/Pastemask Bottom")
		(5 "F.SilkS" user "Ref Des/Silkscreen Top")
		(7 "B.SilkS" user "Ref Des/Silkscreen Bottom")
		(1 "F.Mask" user "Board Geometry/Soldermask Top")
		(3 "B.Mask" user "Board Geometry/Soldermask Bottom")
		(17 "Dwgs.User" user "User.Drawings")
		(19 "Cmts.User" user "User.Comments")
		(21 "Eco1.User" user "User.Eco1")
		(23 "Eco2.User" user "User.Eco2")
		(25 "Edge.Cuts" user "Board Geometry/Outline")
		(27 "Margin" user)
		(31 "F.CrtYd" user "Package Geometry/Place Bound Top")
		(29 "B.CrtYd" user "Package Geometry/Place Bound Bottom")
		(35 "F.Fab" user "Ref Des/Assembly Top")
		(33 "B.Fab" user "Ref Des/Assembly Bottom")
	)
	(footprint ""
		(layer "F.Cu")
		(at 134.1882 -106.172254 -90)
		(property "Reference" "DS9"
			(at -0.126746 2.19583 90)
			(unlocked yes)
			(layer "F.SilkS")
			(effects
				(font
					(size 0.7874 0.5842)
					(thickness 0.1524)
				)
			)
		)
		(property "Value" ""
			(at 0 0 270)
			(layer "F.Fab")
			(effects
				(font
					(size 1.27 1.27)
				)
			)
		)
		(property "User Part Number" "PARTNUM*"
			(at 0.1778 2.422881 270)
			(unlocked yes)
			(layer "Cmts.User")
			(hide yes)
			(effects
				(font
					(size 0.786892 0.583946)
					(thickness 0.000001)
				)
			)
		)
		(property "Device Type" "OPTICAL-G170-10143-01"
			(at 0.1778 1.483081 270)
			(unlocked yes)
			(layer "F.Fab")
			(hide yes)
			(effects
				(font
					(size 0.786892 0.583946)
					(thickness 0.000001)
				)
			)
		)
		(duplicate_pad_numbers_are_jumpers no)
		(fp_line
			(start -1.3208 1.3462)
			(end -2.5908 1.3462)
			(stroke
				(width 0.1)
				(type default)
			)
			(layer "F.SilkS")
		)
		(fp_line
			(start -1.9558 0.7112)
			(end -1.9558 1.9812)
			(stroke
				(width 0.1)
				(type default)
			)
			(layer "F.SilkS")
		)
		(fp_line
			(start -1.397508 0.704088)
			(end -1.397508 -0.704088)
			(stroke
				(width 0.1)
				(type default)
			)
			(layer "F.SilkS")
		)
		(fp_line
			(start 1.397508 0.704088)
			(end -1.397508 0.704088)
			(stroke
				(width 0.1)
				(type default)
			)
			(layer "F.SilkS")
		)
		(fp_line
			(start -1.397508 -0.704088)
			(end 1.397508 -0.704088)
			(stroke
				(width 0.1)
				(type default)
			)
			(layer "F.SilkS")
		)
		(fp_line
			(start 1.397508 -0.704088)
			(end 1.397508 0.704088)
			(stroke
				(width 0.1)
				(type default)
			)
			(layer "F.SilkS")
		)
		(fp_rect
			(start 1.905508 0.704088)
			(end 1.397508 -0.704088)
			(stroke
				(width 0)
				(type default)
			)
			(fill yes)
			(layer "F.SilkS")
		)
		(fp_rect
			(start 1.905508 0.958088)
			(end -1.651508 -0.958088)
			(stroke
				(width 0)
				(type default)
			)
			(fill no)
			(layer "F.CrtYd")
		)
		(fp_line
			(start -0.850138 0.450088)
			(end 0.850138 0.450088)
			(stroke
				(width 0.1)
				(type default)
			)
			(layer "F.Fab")
		)
		(fp_line
			(start 0.850138 0.450088)
			(end 0.850138 -0.450088)
			(stroke
				(width 0.1)
				(type default)
			)
			(layer "F.Fab")
		)
		(fp_line
			(start -2.2098 0.0762)
			(end -3.4798 0.0762)
			(stroke
				(width 0.1)
				(type default)
			)
			(layer "F.Fab")
		)
		(fp_line
			(start -0.850138 -0.450088)
			(end -0.850138 0.450088)
			(stroke
				(width 0.1)
				(type default)
			)
			(layer "F.Fab")
		)
		(fp_line
			(start 0.850138 -0.450088)
			(end -0.850138 -0.450088)
			(stroke
				(width 0.1)
				(type default)
			)
			(layer "F.Fab")
		)
		(fp_line
			(start -2.8448 -0.5588)
			(end -2.8448 0.7112)
			(stroke
				(width 0.1)
				(type default)
			)
			(layer "F.Fab")
		)
		(fp_rect
			(start 0.850138 0.450088)
			(end 0.342138 -0.450088)
			(stroke
				(width 0)
				(type default)
			)
			(fill yes)
			(layer "F.Fab")
		)
		(fp_text user "C"
			(at 2.013204 1.4732 0)
			(unlocked yes)
			(layer "F.SilkS")
			(effects
				(font
					(size 0.635 0.4064)
					(thickness 0.1524)
				)
			)
		)
		(fp_text user "A"
			(at -2.126996 0.2032 0)
			(unlocked yes)
			(layer "F.SilkS")
			(effects
				(font
					(size 0.635 0.4064)
					(thickness 0.1524)
				)
			)
		)
		(fp_text user "A"
			(at -1.497076 0.0762 0)
			(unlocked yes)
			(layer "F.Fab")
			(effects
				(font
					(size 0.7874 0.5842)
					(thickness 0.1524)
				)
			)
		)
		(fp_text user "C"
			(at 1.677924 0.0762 0)
			(unlocked yes)
			(layer "F.Fab")
			(effects
				(font
					(size 0.7874 0.5842)
					(thickness 0.1524)
				)
			)
		)
		(pad "A" smd rect
			(at -0.749808 0 270)
			(size 0.7874 0.7874)
			(layers "F.Cu" "F.Mask" "F.Paste")
			(net "UNNAMED_14_OPTICAL_I292_A")
		)
		(pad "C" smd rect
			(at 0.749808 0 270)
			(size 0.7874 0.7874)
			(layers "F.Cu" "F.Mask" "F.Paste")
			(net "SG")
		)
	)
	(footprint ""
		(layer "F.Cu")
		(at 50.165 -126.873)
		(property "Reference" "SP54"
			(at 0 0 0)
			(layer "F.SilkS")
			(hide yes)
			(effects
				(font
					(size 1.27 1.27)
				)
			)
		)
		(property "Value" ""
			(at 0 0 0)
			(layer "F.Fab")
			(effects
				(font
					(size 1.27 1.27)
				)
			)
		)
		(duplicate_pad_numbers_are_jumpers no)
	)
	(footprint ""
		(layer "F.Cu")
		(at 140.6144 -94.9198 180)
		(property "Reference" "U1"
			(at 3.0734 0.29083 0)
			(unlocked yes)
			(layer "F.SilkS")
			(effects
				(font
					(size 0.7874 0.5842)
					(thickness 0.1524)
				)
			)
		)
		(property "Value" ""
			(at 0 0 180)
			(layer "F.Fab")
			(effects
				(font
					(size 1.27 1.27)
				)
			)
		)
		(property "Device Type" "MP5022CGQV_Z_QFN22-G220-10510-A"
			(at 0.130556 4.082542 180)
			(unlocked yes)
			(layer "F.Fab")
			(hide yes)
			(effects
				(font
					(size 0.7874 0.5842)
					(thickness 0.1524)
				)
			)
		)
		(property "User Part Number" "PARTNUM*"
			(at 0.022352 5.136896 180)
			(unlocked yes)
			(layer "Cmts.User")
			(hide yes)
			(effects
				(font
					(size 0.7874 0.5842)
					(thickness 0.1524)
				)
			)
		)
		(duplicate_pad_numbers_are_jumpers no)
		(fp_line
			(start 2.291334 3.290824)
			(end -2.291334 3.290824)
			(stroke
				(width 0.1)
				(type default)
			)
			(layer "F.SilkS")
		)
		(fp_line
			(start 2.291334 -3.290824)
			(end 2.291334 3.290824)
			(stroke
				(width 0.1)
				(type default)
			)
			(layer "F.SilkS")
		)
		(fp_line
			(start -2.291334 3.290824)
			(end -2.291334 -3.290824)
			(stroke
				(width 0.1)
				(type default)
			)
			(layer "F.SilkS")
		)
		(fp_line
			(start -2.291334 -3.290824)
			(end 2.291334 -3.290824)
			(stroke
				(width 0.1)
				(type default)
			)
			(layer "F.SilkS")
		)
		(fp_poly
			(pts
				(arc
					(start -3.530854 -2.4638)
					(mid -2.514346 -2.4638)
					(end -3.530854 -2.4638)
				)
			)
			(stroke
				(width 0)
				(type default)
			)
			(fill yes)
			(layer "F.SilkS")
		)
		(fp_rect
			(start -0.6223 1.726946)
			(end 0.6223 1.472946)
			(stroke
				(width 0)
				(type default)
			)
			(fill yes)
			(layer "F.Paste")
		)
		(fp_rect
			(start -0.6223 0.827024)
			(end 0.6223 0.573024)
			(stroke
				(width 0)
				(type default)
			)
			(fill yes)
			(layer "F.Paste")
		)
		(fp_rect
			(start -0.6223 -0.072898)
			(end 0.6223 -0.326898)
			(stroke
				(width 0)
				(type default)
			)
			(fill yes)
			(layer "F.Paste")
		)
		(fp_rect
			(start -0.6223 -0.973074)
			(end 0.6223 -1.227074)
			(stroke
				(width 0)
				(type default)
			)
			(fill yes)
			(layer "F.Paste")
		)
		(fp_poly
			(pts
				(xy -2.545334 3.544824) (xy 2.545334 3.544824) (xy 2.545334 -3.544824) (xy -2.545334 -3.544824)
			)
			(stroke
				(width 0)
				(type default)
			)
			(fill no)
			(layer "F.CrtYd")
		)
		(fp_line
			(start 1.549908 2.549906)
			(end 1.549908 -2.549906)
			(stroke
				(width 0.1)
				(type default)
			)
			(layer "F.Fab")
		)
		(fp_line
			(start 1.549908 -2.549906)
			(end -1.549908 -2.549906)
			(stroke
				(width 0.1)
				(type default)
			)
			(layer "F.Fab")
		)
		(fp_line
			(start -1.549908 2.549906)
			(end 1.549908 2.549906)
			(stroke
				(width 0.1)
				(type default)
			)
			(layer "F.Fab")
		)
		(fp_line
			(start -1.549908 -2.549906)
			(end -1.549908 2.549906)
			(stroke
				(width 0.1)
				(type default)
			)
			(layer "F.Fab")
		)
		(fp_poly
			(pts
				(arc
					(start -3.709162 -1.999996)
					(mid -2.692654 -1.999996)
					(end -3.709162 -1.999996)
				)
			)
			(stroke
				(width 0)
				(type default)
			)
			(fill yes)
			(layer "F.Fab")
		)
		(fp_text user "20"
			(at 3.0734 -1.60655 0)
			(unlocked yes)
			(layer "F.SilkS")
			(effects
				(font
					(size 0.635 0.4064)
					(thickness 0.1524)
				)
			)
		)
		(fp_text user "12"
			(at 2.9464 2.20345 0)
			(unlocked yes)
			(layer "F.SilkS")
			(effects
				(font
					(size 0.635 0.4064)
					(thickness 0.1524)
				)
			)
		)
		(fp_text user "9"
			(at -2.8956 2.20345 0)
			(unlocked yes)
			(layer "F.SilkS")
			(effects
				(font
					(size 0.635 0.4064)
					(thickness 0.1524)
				)
			)
		)
		(fp_text user "12"
			(at 3.193034 2.210054 0)
			(unlocked yes)
			(layer "F.Fab")
			(effects
				(font
					(size 0.7874 0.5842)
					(thickness 0.1524)
				)
			)
		)
		(fp_text user "20"
			(at 3.193034 -1.789938 0)
			(unlocked yes)
			(layer "F.Fab")
			(effects
				(font
					(size 0.7874 0.5842)
					(thickness 0.1524)
				)
			)
		)
		(fp_text user "9"
			(at -3.193034 2.210054 0)
			(unlocked yes)
			(layer "F.Fab")
			(effects
				(font
					(size 0.7874 0.5842)
					(thickness 0.1524)
				)
			)
		)
		(pad "1" smd rect
			(at -1.440434 -1.999996 180)
			(size 1.1938 0.3048)
			(layers "F.Cu" "F.Mask" "F.Paste")
			(net "XP12R0V_A_EN")
		)
		(pad "2" smd rect
			(at -1.440434 -1.500124 180)
			(size 1.1938 0.3048)
			(layers "F.Cu" "F.Mask" "F.Paste")
			(net "UNNAMED_15_MP5022CGQVZQFN22_I_2")
		)
		(pad "3" smd rect
			(at -1.440434 -0.999998 180)
			(size 1.1938 0.3048)
			(layers "F.Cu" "F.Mask" "F.Paste")
			(net "UNNAMED_15_MP5022CGQVZQFN22_I21")
		)
		(pad "4" smd rect
			(at -1.440434 -0.500126 180)
			(size 1.1938 0.3048)
			(layers "F.Cu" "F.Mask" "F.Paste")
			(net "XP12R0V_A_TIMER")
		)
		(pad "5" smd rect
			(at -1.440434 0 180)
			(size 1.1938 0.3048)
			(layers "F.Cu" "F.Mask" "F.Paste")
			(net "XP12R0V_A_ISET")
		)
		(pad "6" smd rect
			(at -1.440434 0.500126 180)
			(size 1.1938 0.3048)
			(layers "F.Cu" "F.Mask" "F.Paste")
			(net "XP12R0V_A_SS")
		)
		(pad "7" smd rect
			(at -1.440434 0.999998 180)
			(size 1.1938 0.3048)
			(layers "F.Cu" "F.Mask" "F.Paste")
			(net "SG")
		)
		(pad "8" smd rect
			(at -1.440434 1.500124 180)
			(size 1.1938 0.3048)
			(layers "F.Cu" "F.Mask" "F.Paste")
			(net "XP12R0V_A_IMON")
		)
		(pad "9" smd rect
			(at -1.440434 1.999996 180)
			(size 1.1938 0.3048)
			(layers "F.Cu" "F.Mask" "F.Paste")
			(net "XP12R0V_A_FLTB")
		)
		(pad "10" smd rect
			(at -0.500126 2.478024 180)
			(size 0.3302 1.1176)
			(layers "F.Cu" "F.Mask" "F.Paste")
			(net "XP12R0V_A_PG")
		)
		(pad "11" smd rect
			(at 0.500126 2.478024 180)
			(size 0.3302 1.1176)
			(layers "F.Cu" "F.Mask" "F.Paste")
			(net "XP12R0V_A_OV")
		)
		(pad "12" smd rect
			(at 1.440434 1.999996 180)
			(size 1.1938 0.3048)
			(layers "F.Cu" "F.Mask" "F.Paste")
			(net "XP12R0V_A_AVIN")
		)
		(pad "13" smd rect
			(at 1.440434 1.500124 180)
			(size 1.1938 0.3048)
			(layers "F.Cu" "F.Mask" "F.Paste")
			(net "XP12R0V")
		)
		(pad "14" smd rect
			(at 1.440434 0.999998 180)
			(size 1.1938 0.3048)
			(layers "F.Cu" "F.Mask" "F.Paste")
			(net "XP12R0V")
		)
		(pad "15" smd rect
			(at 1.440434 0.500126 180)
			(size 1.1938 0.3048)
			(layers "F.Cu" "F.Mask" "F.Paste")
			(net "XP12R0V")
		)
		(pad "16" smd rect
			(at 1.440434 0 180)
			(size 1.1938 0.3048)
			(layers "F.Cu" "F.Mask" "F.Paste")
			(net "XP12R0V")
		)
		(pad "17" smd rect
			(at 1.440434 -0.500126 180)
			(size 1.1938 0.3048)
			(layers "F.Cu" "F.Mask" "F.Paste")
			(net "XP12R0V")
		)
		(pad "18" smd rect
			(at 1.440434 -0.999998 180)
			(size 1.1938 0.3048)
			(layers "F.Cu" "F.Mask" "F.Paste")
			(net "XP12R0V")
		)
		(pad "19" smd rect
			(at 1.440434 -1.500124 180)
			(size 1.1938 0.3048)
			(layers "F.Cu" "F.Mask" "F.Paste")
			(net "XP12R0V")
		)
		(pad "20" smd rect
			(at 1.440434 -1.999996 180)
			(size 1.1938 0.3048)
			(layers "F.Cu" "F.Mask" "F.Paste")
			(net "XP12R0V")
		)
		(pad "21" smd circle
			(at 0 -2.003298 180)
			(size 0 0)
			(layers "F.Cu" "F.Mask" "F.Paste")
			(net "XP12R0V_IN")
		)
		(pad "22" smd rect
			(at -0.509778 -2.64033 180)
			(size 0.0254 0.0254)
			(layers "F.Cu" "F.Mask" "F.Paste")
			(net "XP12R0V_IN")
		)
		(pad "23" smd rect
			(at 0 -1.100074 180)
			(size 1.2446 0.254)
			(layers "F.Cu" "F.Mask" "F.Paste")
			(net "XP12R0V_IN")
		)
		(pad "24" smd rect
			(at 0 -0.199898 180)
			(size 1.2446 0.254)
			(layers "F.Cu" "F.Mask" "F.Paste")
			(net "XP12R0V_IN")
		)
		(pad "25" smd rect
			(at 0 0.700024 180)
			(size 1.2446 0.254)
			(layers "F.Cu" "F.Mask" "F.Paste")
			(net "XP12R0V_IN")
		)
		(pad "26" smd rect
			(at 0 1.599946 180)
			(size 1.2446 0.254)
			(layers "F.Cu" "F.Mask" "F.Paste")
			(net "XP12R0V_IN")
		)
	)
	(footprint ""
		(layer "F.Cu")
		(at 134.0612 -66.8528 90)
		(property "Reference" "R187"
			(at -4.8768 0.59817 90)
			(unlocked yes)
			(layer "F.SilkS")
			(effects
				(font
					(size 0.7874 0.5842)
					(thickness 0.1524)
				)
			)
		)
		(property "Value" "VAL*"
			(at 0.0508 2.245106 90)
			(unlocked yes)
			(layer "F.Fab")
			(hide yes)
			(effects
				(font
					(size 0.7874 0.5842)
					(thickness 0.1524)
				)
			)
		)
		(property "User Part Number" "PARTNUM*"
			(at 0.0762 4.302506 90)
			(unlocked yes)
			(layer "Cmts.User")
			(hide yes)
			(effects
				(font
					(size 0.7874 0.5842)
					(thickness 0.1524)
				)
			)
		)
		(property "Device Type" "RESISTOR-G155-04221-01,4.22KOHA"
			(at 0.0762 1.254506 90)
			(unlocked yes)
			(layer "F.Fab")
			(hide yes)
			(effects
				(font
					(size 0.7874 0.5842)
					(thickness 0.1524)
				)
			)
		)
		(property "Tolerance" "TOL*"
			(at 0.0508 3.261106 90)
			(unlocked yes)
			(layer "Cmts.User")
			(hide yes)
			(effects
				(font
					(size 0.7874 0.5842)
					(thickness 0.1524)
				)
			)
		)
		(duplicate_pad_numbers_are_jumpers no)
		(fp_line
			(start 1.143 -0.5588)
			(end -1.143 -0.5588)
			(stroke
				(width 0.1)
				(type default)
			)
			(layer "F.SilkS")
		)
		(fp_line
			(start -1.143 -0.5588)
			(end -1.143 0.5588)
			(stroke
				(width 0.1)
				(type default)
			)
			(layer "F.SilkS")
		)
		(fp_line
			(start 1.143 0.5588)
			(end 1.143 -0.5588)
			(stroke
				(width 0.1)
				(type default)
			)
			(layer "F.SilkS")
		)
		(fp_line
			(start -1.143 0.5588)
			(end 1.143 0.5588)
			(stroke
				(width 0.1)
				(type default)
			)
			(layer "F.SilkS")
		)
		(fp_rect
			(start 1.143 0.5588)
			(end -1.143 -0.5588)
			(stroke
				(width 0)
				(type default)
			)
			(fill no)
			(layer "F.CrtYd")
		)
		(fp_line
			(start 0.508 -0.3048)
			(end -0.508 -0.3048)
			(stroke
				(width 0.1)
				(type default)
			)
			(layer "F.Fab")
		)
		(fp_line
			(start -0.508 -0.3048)
			(end -0.508 0.3048)
			(stroke
				(width 0.1)
				(type default)
			)
			(layer "F.Fab")
		)
		(fp_line
			(start 0.508 0.3048)
			(end 0.508 -0.3048)
			(stroke
				(width 0.1)
				(type default)
			)
			(layer "F.Fab")
		)
		(fp_line
			(start -0.508 0.3048)
			(end 0.508 0.3048)
			(stroke
				(width 0.1)
				(type default)
			)
			(layer "F.Fab")
		)
		(pad "1" smd rect
			(at -0.5334 0 90)
			(size 0.7112 0.6096)
			(layers "F.Cu" "F.Mask" "F.Paste")
			(net "XP1R8V_FPGA")
		)
		(pad "2" smd rect
			(at 0.5334 0 90)
			(size 0.7112 0.6096)
			(layers "F.Cu" "F.Mask" "F.Paste")
			(net "XP1R8V_FB")
		)
		(zone
			(layer "F.Cu")
			(hatch none 0.5)
			(connect_pads
				(clearance 0)
			)
			(min_thickness 0.25)
			(keepout
				(tracks allowed)
				(vias not_allowed)
				(pads allowed)
				(copperpour not_allowed)
				(footprints allowed)
			)
			(placement
				(enabled no)
				(sheetname "")
			)
			(fill
				(thermal_gap 0.5)
				(thermal_bridge_width 0.5)
				(island_removal_mode 0)
			)
			(polygon
				(pts
					(xy 134.366 -66.929) (xy 133.7564 -66.929) (xy 133.7564 -66.7766) (xy 134.366 -66.7766)
				)
			)
		)
	)
)
